(kicad_pcb
	(version 20260206)
	(generator "pcbnew")
	(generator_version "10.0")
	(general
		(thickness 1.6)
		(legacy_teardrops no)
	)
	(paper "A4")
	(title_block
		(title "04192023_DAF0TMB3IC0_F0TG_MB_C_brd_V02_OCP.brd")
		(comment 1 "Grand Teton / footprint 2783 of 8354 (U26), pads 5012-5123 of 6102")
	)
	(layers
		(0 "F.Cu" signal "TOP")
		(4 "In1.Cu" signal "GND")
		(6 "In2.Cu" signal "IN1")
		(8 "In3.Cu" signal "GND1")
		(10 "In4.Cu" signal "IN2")
		(12 "In5.Cu" signal "GND2")
		(14 "In6.Cu" signal "IN3")
		(16 "In7.Cu" signal "GND3")
		(18 "In8.Cu" signal "VCC")
		(20 "In9.Cu" signal "VCC1")
		(22 "In10.Cu" signal "GND4")
		(24 "In11.Cu" signal "IN4")
		(26 "In12.Cu" signal "GND5")
		(28 "In13.Cu" signal "IN5")
		(30 "In14.Cu" signal "GND6")
		(32 "In15.Cu" signal "IN6")
		(34 "In16.Cu" signal "GND7")
		(2 "B.Cu" signal "BOTTOM")
		(9 "F.Adhes" user "F.Adhesive")
		(11 "B.Adhes" user "B.Adhesive")
		(13 "F.Paste" user "Package Geometry/Pastemask Top")
		(15 "B.Paste" user "Package Geometry/Pastemask Bottom")
		(5 "F.SilkS" user "Ref Des/Silkscreen Top")
		(7 "B.SilkS" user "Ref Des/Silkscreen Bottom")
		(1 "F.Mask" user "Board Geometry/Soldermask Top")
		(3 "B.Mask" user "Board Geometry/Soldermask Bottom")
		(17 "Dwgs.User" user "User.Drawings")
		(19 "Cmts.User" user "User.Comments")
		(21 "Eco1.User" user "User.Eco1")
		(23 "Eco2.User" user "User.Eco2")
		(25 "Edge.Cuts" user "Board Geometry/Outline")
		(27 "Margin" user)
		(31 "F.CrtYd" user "Package Geometry/Place Bound Top")
		(29 "B.CrtYd" user "Package Geometry/Place Bound Bottom")
		(35 "F.Fab" user "Ref Des/Assembly Top")
		(33 "B.Fab" user "Ref Des/Assembly Bottom")
	)
	(footprint ""
		(layer "F.Cu")
		(at 111.927894 -258.880356 180)
		(property "Reference" "U26"
			(at -45.05579 -61.794136 0)
			(unlocked yes)
			(layer "F.SilkS")
			(effects
				(font
					(size 0.7874 0.5842)
					(thickness 0.1524)
				)
			)
		)
		(property "Value" ""
			(at 0 0 180)
			(layer "F.Fab")
			(effects
				(font
					(size 1.27 1.27)
				)
			)
		)
		(duplicate_pad_numbers_are_jumpers no)
		(pad "E65" smd circle
			(at 25.059894 -33.56991 180)
			(size 0.450088 0.450088)
			(layers "F.Cu" "F.Mask" "F.Paste")
			(net "GND")
		)
		(pad "E66" smd circle
			(at 25.999948 -33.56991 180)
			(size 0.450088 0.450088)
			(layers "F.Cu" "F.Mask" "F.Paste")
			(net "GND")
		)
		(pad "E67" smd circle
			(at 26.940002 -33.56991 180)
			(size 0.450088 0.450088)
			(layers "F.Cu" "F.Mask" "F.Paste")
			(net "M_F_CPU1_SA_DQ<0>")
		)
		(pad "E68" smd circle
			(at 27.880056 -33.56991 180)
			(size 0.450088 0.450088)
			(layers "F.Cu" "F.Mask" "F.Paste")
			(net "GND")
		)
		(pad "E69" smd circle
			(at 28.82011 -33.56991 180)
			(size 0.450088 0.450088)
			(layers "F.Cu" "F.Mask" "F.Paste")
			(net "GND")
		)
		(pad "E70" smd circle
			(at 29.75991 -33.56991 180)
			(size 0.450088 0.450088)
			(layers "F.Cu" "F.Mask" "F.Paste")
			(net "GND")
		)
		(pad "E71" smd circle
			(at 30.699964 -33.56991 180)
			(size 0.450088 0.450088)
			(layers "F.Cu" "F.Mask" "F.Paste")
			(net "M_E_CPU1_SA_DQ<0>")
		)
		(pad "E72" smd circle
			(at 31.640018 -33.56991 180)
			(size 0.450088 0.450088)
			(layers "F.Cu" "F.Mask" "F.Paste")
			(net "GND")
		)
		(pad "E73" smd circle
			(at 32.580072 -33.56991 180)
			(size 0.450088 0.450088)
			(layers "F.Cu" "F.Mask" "F.Paste")
			(net "GND")
		)
		(pad "E74" smd circle
			(at 33.519872 -33.56991 180)
			(size 0.450088 0.450088)
			(layers "F.Cu" "F.Mask" "F.Paste")
			(net "M_A_CPU1_SA_DQ<0>")
		)
		(pad "E75" smd circle
			(at 34.459926 -33.56991 180)
			(size 0.450088 0.450088)
			(layers "F.Cu" "F.Mask" "F.Paste")
			(net "GND")
		)
		(pad "F2" smd circle
			(at -33.690052 -32.759904 180)
			(size 0.450088 0.450088)
			(layers "F.Cu" "F.Mask" "F.Paste")
			(net "M_G_CPU1_SA_DQ<2>")
		)
		(pad "F3" smd circle
			(at -32.749998 -32.759904 180)
			(size 0.450088 0.450088)
			(layers "F.Cu" "F.Mask" "F.Paste")
			(net "GND")
		)
		(pad "F4" smd circle
			(at -31.809944 -32.759904 180)
			(size 0.450088 0.450088)
			(layers "F.Cu" "F.Mask" "F.Paste")
			(net "M_G_CPU1_SA_DQ<1>")
		)
		(pad "F5" smd circle
			(at -30.86989 -32.759904 180)
			(size 0.450088 0.450088)
			(layers "F.Cu" "F.Mask" "F.Paste")
			(net "GND")
		)
		(pad "F6" smd circle
			(at -29.93009 -32.759904 180)
			(size 0.450088 0.450088)
			(layers "F.Cu" "F.Mask" "F.Paste")
			(net "M_K_CPU1_SA_DQ<2>")
		)
		(pad "F7" smd circle
			(at -28.990036 -32.759904 180)
			(size 0.450088 0.450088)
			(layers "F.Cu" "F.Mask" "F.Paste")
			(net "M_K_CPU1_SA_DQ<1>")
		)
		(pad "F8" smd circle
			(at -28.049982 -32.759904 180)
			(size 0.450088 0.450088)
			(layers "F.Cu" "F.Mask" "F.Paste")
			(net "GND")
		)
		(pad "F9" smd circle
			(at -27.109928 -32.759904 180)
			(size 0.450088 0.450088)
			(layers "F.Cu" "F.Mask" "F.Paste")
			(net "M_L_CPU1_SA_DQ<2>")
		)
		(pad "F10" smd circle
			(at -26.170128 -32.759904 180)
			(size 0.450088 0.450088)
			(layers "F.Cu" "F.Mask" "F.Paste")
			(net "GND")
		)
		(pad "F11" smd circle
			(at -25.230074 -32.759904 180)
			(size 0.450088 0.450088)
			(layers "F.Cu" "F.Mask" "F.Paste")
			(net "M_L_CPU1_SA_DQ<1>")
		)
		(pad "F12" smd circle
			(at -24.29002 -32.759904 180)
			(size 0.450088 0.450088)
			(layers "F.Cu" "F.Mask" "F.Paste")
			(net "GND")
		)
		(pad "F13" smd circle
			(at -23.349966 -32.759904 180)
			(size 0.450088 0.450088)
			(layers "F.Cu" "F.Mask" "F.Paste")
			(net "M_H_CPU1_SA_DQ<2>")
		)
		(pad "F14" smd circle
			(at -22.409912 -32.759904 180)
			(size 0.450088 0.450088)
			(layers "F.Cu" "F.Mask" "F.Paste")
			(net "M_H_CPU1_SA_DQ<1>")
		)
		(pad "F15" smd circle
			(at -21.470112 -32.759904 180)
			(size 0.450088 0.450088)
			(layers "F.Cu" "F.Mask" "F.Paste")
			(net "GND")
		)
		(pad "F16" smd circle
			(at -20.530058 -32.759904 180)
			(size 0.450088 0.450088)
			(layers "F.Cu" "F.Mask" "F.Paste")
			(net "M_J_CPU1_SA_DQ<2>")
		)
		(pad "F17" smd circle
			(at -19.590004 -32.759904 180)
			(size 0.450088 0.450088)
			(layers "F.Cu" "F.Mask" "F.Paste")
			(net "GND")
		)
		(pad "F18" smd circle
			(at -18.64995 -32.759904 180)
			(size 0.450088 0.450088)
			(layers "F.Cu" "F.Mask" "F.Paste")
			(net "M_J_CPU1_SA_DQ<1>")
		)
		(pad "F19" smd circle
			(at -17.709896 -32.759904 180)
			(size 0.450088 0.450088)
			(layers "F.Cu" "F.Mask" "F.Paste")
			(net "GND")
		)
		(pad "F20" smd circle
			(at -16.770096 -32.759904 180)
			(size 0.450088 0.450088)
			(layers "F.Cu" "F.Mask" "F.Paste")
			(net "M_I_CPU1_SA_DQ<2>")
		)
		(pad "F21" smd circle
			(at -15.830042 -32.759904 180)
			(size 0.450088 0.450088)
			(layers "F.Cu" "F.Mask" "F.Paste")
			(net "M_I_CPU1_SA_DQ<1>")
		)
		(pad "F22" smd circle
			(at -14.889988 -32.759904 180)
			(size 0.450088 0.450088)
			(layers "F.Cu" "F.Mask" "F.Paste")
			(net "PVDDCR_CPU0_P1")
		)
		(pad "F23" smd circle
			(at -13.949934 -32.759904 180)
			(size 0.450088 0.450088)
			(layers "F.Cu" "F.Mask" "F.Paste")
			(net "GND")
		)
		(pad "F24" smd circle
			(at -13.00988 -32.759904 180)
			(size 0.450088 0.450088)
			(layers "F.Cu" "F.Mask" "F.Paste")
			(net "GND")
		)
		(pad "F25" smd circle
			(at -12.07008 -32.759904 180)
			(size 0.450088 0.450088)
			(layers "F.Cu" "F.Mask" "F.Paste")
			(net "PVDDCR_CPU0_P1")
		)
		(pad "F26" smd circle
			(at -11.130026 -32.759904 180)
			(size 0.450088 0.450088)
			(layers "F.Cu" "F.Mask" "F.Paste")
			(net "GND")
		)
		(pad "F27" smd circle
			(at -10.189972 -32.759904 180)
			(size 0.450088 0.450088)
			(layers "F.Cu" "F.Mask" "F.Paste")
			(net "GND")
		)
		(pad "F28" smd circle
			(at -9.249918 -32.759904 180)
			(size 0.450088 0.450088)
			(layers "F.Cu" "F.Mask" "F.Paste")
			(net "PVDDCR_CPU0_P1")
		)
		(pad "F29" smd circle
			(at -8.310118 -32.759904 180)
			(size 0.450088 0.450088)
			(layers "F.Cu" "F.Mask" "F.Paste")
			(net "GND")
		)
		(pad "F30" smd circle
			(at -7.370064 -32.759904 180)
			(size 0.450088 0.450088)
			(layers "F.Cu" "F.Mask" "F.Paste")
			(net "GND")
		)
		(pad "F31" smd circle
			(at -6.43001 -32.759904 180)
			(size 0.450088 0.450088)
			(layers "F.Cu" "F.Mask" "F.Paste")
			(net "PVDDCR_CPU0_P1")
		)
		(pad "F32" smd circle
			(at -5.489956 -32.759904 180)
			(size 0.450088 0.450088)
			(layers "F.Cu" "F.Mask" "F.Paste")
			(net "GND")
		)
		(pad "F33" smd circle
			(at -4.549902 -32.759904 180)
			(size 0.450088 0.450088)
			(layers "F.Cu" "F.Mask" "F.Paste")
			(net "GND")
		)
		(pad "F34" smd circle
			(at -3.610102 -32.759904 180)
			(size 0.450088 0.450088)
			(layers "F.Cu" "F.Mask" "F.Paste")
			(net "PVDDCR_CPU0_P1")
		)
		(pad "F35" smd circle
			(at -2.670048 -32.759904 180)
			(size 0.450088 0.450088)
			(layers "F.Cu" "F.Mask" "F.Paste")
			(net "GND")
		)
		(pad "F36" smd circle
			(at -1.729994 -32.759904 180)
			(size 0.450088 0.450088)
			(layers "F.Cu" "F.Mask" "F.Paste")
			(net "GND")
		)
		(pad "F37" smd circle
			(at -0.78994 -32.759904 180)
			(size 0.450088 0.450088)
			(layers "F.Cu" "F.Mask" "F.Paste")
			(net "GND")
		)
		(pad "F39" smd circle
			(at 1.089914 -32.759904 180)
			(size 0.450088 0.450088)
			(layers "F.Cu" "F.Mask" "F.Paste")
			(net "GND")
		)
		(pad "F40" smd circle
			(at 2.029968 -32.759904 180)
			(size 0.450088 0.450088)
			(layers "F.Cu" "F.Mask" "F.Paste")
			(net "GND")
		)
		(pad "F41" smd circle
			(at 2.970022 -32.759904 180)
			(size 0.450088 0.450088)
			(layers "F.Cu" "F.Mask" "F.Paste")
			(net "GND")
		)
		(pad "F42" smd circle
			(at 3.910076 -32.759904 180)
			(size 0.450088 0.450088)
			(layers "F.Cu" "F.Mask" "F.Paste")
			(net "PVDDCR_CPU0_P1")
		)
		(pad "F43" smd circle
			(at 4.849876 -32.759904 180)
			(size 0.450088 0.450088)
			(layers "F.Cu" "F.Mask" "F.Paste")
			(net "GND")
		)
		(pad "F44" smd circle
			(at 5.78993 -32.759904 180)
			(size 0.450088 0.450088)
			(layers "F.Cu" "F.Mask" "F.Paste")
			(net "GND")
		)
		(pad "F45" smd circle
			(at 6.729984 -32.759904 180)
			(size 0.450088 0.450088)
			(layers "F.Cu" "F.Mask" "F.Paste")
			(net "PVDDCR_CPU0_P1")
		)
		(pad "F46" smd circle
			(at 7.670038 -32.759904 180)
			(size 0.450088 0.450088)
			(layers "F.Cu" "F.Mask" "F.Paste")
			(net "GND")
		)
		(pad "F47" smd circle
			(at 8.610092 -32.759904 180)
			(size 0.450088 0.450088)
			(layers "F.Cu" "F.Mask" "F.Paste")
			(net "GND")
		)
		(pad "F48" smd circle
			(at 9.549892 -32.759904 180)
			(size 0.450088 0.450088)
			(layers "F.Cu" "F.Mask" "F.Paste")
			(net "PVDDCR_CPU0_P1")
		)
		(pad "F49" smd circle
			(at 10.489946 -32.759904 180)
			(size 0.450088 0.450088)
			(layers "F.Cu" "F.Mask" "F.Paste")
			(net "GND")
		)
		(pad "F50" smd circle
			(at 11.43 -32.759904 180)
			(size 0.450088 0.450088)
			(layers "F.Cu" "F.Mask" "F.Paste")
			(net "GND")
		)
		(pad "F51" smd circle
			(at 12.370054 -32.759904 180)
			(size 0.450088 0.450088)
			(layers "F.Cu" "F.Mask" "F.Paste")
			(net "PVDDCR_CPU0_P1")
		)
		(pad "F52" smd circle
			(at 13.310108 -32.759904 180)
			(size 0.450088 0.450088)
			(layers "F.Cu" "F.Mask" "F.Paste")
			(net "GND")
		)
		(pad "F53" smd circle
			(at 14.249908 -32.759904 180)
			(size 0.450088 0.450088)
			(layers "F.Cu" "F.Mask" "F.Paste")
			(net "GND")
		)
		(pad "F54" smd circle
			(at 15.189962 -32.759904 180)
			(size 0.450088 0.450088)
			(layers "F.Cu" "F.Mask" "F.Paste")
			(net "PVDDCR_CPU0_P1")
		)
		(pad "F55" smd circle
			(at 16.130016 -32.759904 180)
			(size 0.450088 0.450088)
			(layers "F.Cu" "F.Mask" "F.Paste")
			(net "M_C_CPU1_SA_DQ<1>")
		)
		(pad "F56" smd circle
			(at 17.07007 -32.759904 180)
			(size 0.450088 0.450088)
			(layers "F.Cu" "F.Mask" "F.Paste")
			(net "M_C_CPU1_SA_DQ<2>")
		)
		(pad "F57" smd circle
			(at 18.010124 -32.759904 180)
			(size 0.450088 0.450088)
			(layers "F.Cu" "F.Mask" "F.Paste")
			(net "GND")
		)
		(pad "F58" smd circle
			(at 18.949924 -32.759904 180)
			(size 0.450088 0.450088)
			(layers "F.Cu" "F.Mask" "F.Paste")
			(net "M_D_CPU1_SA_DQ<1>")
		)
		(pad "F59" smd circle
			(at 19.889978 -32.759904 180)
			(size 0.450088 0.450088)
			(layers "F.Cu" "F.Mask" "F.Paste")
			(net "GND")
		)
		(pad "F60" smd circle
			(at 20.830032 -32.759904 180)
			(size 0.450088 0.450088)
			(layers "F.Cu" "F.Mask" "F.Paste")
			(net "M_D_CPU1_SA_DQ<2>")
		)
		(pad "F61" smd circle
			(at 21.770086 -32.759904 180)
			(size 0.450088 0.450088)
			(layers "F.Cu" "F.Mask" "F.Paste")
			(net "GND")
		)
		(pad "F62" smd circle
			(at 22.709886 -32.759904 180)
			(size 0.450088 0.450088)
			(layers "F.Cu" "F.Mask" "F.Paste")
			(net "M_B_CPU1_SA_DQ<1>")
		)
		(pad "F63" smd circle
			(at 23.64994 -32.759904 180)
			(size 0.450088 0.450088)
			(layers "F.Cu" "F.Mask" "F.Paste")
			(net "M_B_CPU1_SA_DQ<2>")
		)
		(pad "F64" smd circle
			(at 24.589994 -32.759904 180)
			(size 0.450088 0.450088)
			(layers "F.Cu" "F.Mask" "F.Paste")
			(net "GND")
		)
		(pad "F65" smd circle
			(at 25.530048 -32.759904 180)
			(size 0.450088 0.450088)
			(layers "F.Cu" "F.Mask" "F.Paste")
			(net "M_F_CPU1_SA_DQ<1>")
		)
		(pad "F66" smd circle
			(at 26.470102 -32.759904 180)
			(size 0.450088 0.450088)
			(layers "F.Cu" "F.Mask" "F.Paste")
			(net "GND")
		)
		(pad "F67" smd circle
			(at 27.409902 -32.759904 180)
			(size 0.450088 0.450088)
			(layers "F.Cu" "F.Mask" "F.Paste")
			(net "M_F_CPU1_SA_DQ<2>")
		)
		(pad "F68" smd circle
			(at 28.349956 -32.759904 180)
			(size 0.450088 0.450088)
			(layers "F.Cu" "F.Mask" "F.Paste")
			(net "GND")
		)
		(pad "F69" smd circle
			(at 29.29001 -32.759904 180)
			(size 0.450088 0.450088)
			(layers "F.Cu" "F.Mask" "F.Paste")
			(net "M_E_CPU1_SA_DQ<1>")
		)
		(pad "F70" smd circle
			(at 30.230064 -32.759904 180)
			(size 0.450088 0.450088)
			(layers "F.Cu" "F.Mask" "F.Paste")
			(net "M_E_CPU1_SA_DQ<2>")
		)
		(pad "F71" smd circle
			(at 31.170118 -32.759904 180)
			(size 0.450088 0.450088)
			(layers "F.Cu" "F.Mask" "F.Paste")
			(net "GND")
		)
		(pad "F72" smd circle
			(at 32.109918 -32.759904 180)
			(size 0.450088 0.450088)
			(layers "F.Cu" "F.Mask" "F.Paste")
			(net "M_A_CPU1_SA_DQ<1>")
		)
		(pad "F73" smd circle
			(at 33.049972 -32.759904 180)
			(size 0.450088 0.450088)
			(layers "F.Cu" "F.Mask" "F.Paste")
			(net "GND")
		)
		(pad "F74" smd circle
			(at 33.990026 -32.759904 180)
			(size 0.450088 0.450088)
			(layers "F.Cu" "F.Mask" "F.Paste")
			(net "M_A_CPU1_SA_DQ<2>")
		)
		(pad "G1" smd circle
			(at -34.159952 -31.949898 180)
			(size 0.450088 0.450088)
			(layers "F.Cu" "F.Mask" "F.Paste")
			(net "GND")
		)
		(pad "G2" smd circle
			(at -33.219898 -31.949898 180)
			(size 0.450088 0.450088)
			(layers "F.Cu" "F.Mask" "F.Paste")
			(net "M_G_CPU1_SA_DQS_DP<0>")
		)
		(pad "G3" smd circle
			(at -32.280098 -31.949898 180)
			(size 0.450088 0.450088)
			(layers "F.Cu" "F.Mask" "F.Paste")
			(net "M_G_CPU1_SA_DQ<3>")
		)
		(pad "G4" smd circle
			(at -31.340044 -31.949898 180)
			(size 0.450088 0.450088)
			(layers "F.Cu" "F.Mask" "F.Paste")
			(net "GND")
		)
		(pad "G5" smd circle
			(at -30.39999 -31.949898 180)
			(size 0.450088 0.450088)
			(layers "F.Cu" "F.Mask" "F.Paste")
			(net "M_K_CPU1_SA_DQS_DP<0>")
		)
		(pad "G6" smd circle
			(at -29.459936 -31.949898 180)
			(size 0.450088 0.450088)
			(layers "F.Cu" "F.Mask" "F.Paste")
			(net "GND")
		)
		(pad "G7" smd circle
			(at -28.519882 -31.949898 180)
			(size 0.450088 0.450088)
			(layers "F.Cu" "F.Mask" "F.Paste")
			(net "M_K_CPU1_SA_DQ<3>")
		)
		(pad "G8" smd circle
			(at -27.580082 -31.949898 180)
			(size 0.450088 0.450088)
			(layers "F.Cu" "F.Mask" "F.Paste")
			(net "GND")
		)
		(pad "G9" smd circle
			(at -26.640028 -31.949898 180)
			(size 0.450088 0.450088)
			(layers "F.Cu" "F.Mask" "F.Paste")
			(net "M_L_CPU1_SA_DQS_DP<0>")
		)
		(pad "G10" smd circle
			(at -25.699974 -31.949898 180)
			(size 0.450088 0.450088)
			(layers "F.Cu" "F.Mask" "F.Paste")
			(net "M_L_CPU1_SA_DQ<3>")
		)
		(pad "G11" smd circle
			(at -24.75992 -31.949898 180)
			(size 0.450088 0.450088)
			(layers "F.Cu" "F.Mask" "F.Paste")
			(net "GND")
		)
		(pad "G12" smd circle
			(at -23.82012 -31.949898 180)
			(size 0.450088 0.450088)
			(layers "F.Cu" "F.Mask" "F.Paste")
			(net "M_H_CPU1_SA_DQS_DP<0>")
		)
		(pad "G13" smd circle
			(at -22.880066 -31.949898 180)
			(size 0.450088 0.450088)
			(layers "F.Cu" "F.Mask" "F.Paste")
			(net "GND")
		)
		(pad "G14" smd circle
			(at -21.940012 -31.949898 180)
			(size 0.450088 0.450088)
			(layers "F.Cu" "F.Mask" "F.Paste")
			(net "M_H_CPU1_SA_DQ<3>")
		)
		(pad "G15" smd circle
			(at -20.999958 -31.949898 180)
			(size 0.450088 0.450088)
			(layers "F.Cu" "F.Mask" "F.Paste")
			(net "GND")
		)
		(pad "G16" smd circle
			(at -20.059904 -31.949898 180)
			(size 0.450088 0.450088)
			(layers "F.Cu" "F.Mask" "F.Paste")
			(net "M_J_CPU1_SA_DQS_DP<0>")
		)
		(pad "G17" smd circle
			(at -19.120104 -31.949898 180)
			(size 0.450088 0.450088)
			(layers "F.Cu" "F.Mask" "F.Paste")
			(net "M_J_CPU1_SA_DQ<3>")
		)
		(pad "G18" smd circle
			(at -18.18005 -31.949898 180)
			(size 0.450088 0.450088)
			(layers "F.Cu" "F.Mask" "F.Paste")
			(net "GND")
		)
		(pad "G19" smd circle
			(at -17.239996 -31.949898 180)
			(size 0.450088 0.450088)
			(layers "F.Cu" "F.Mask" "F.Paste")
			(net "M_I_CPU1_SA_DQS_DP<0>")
		)
		(pad "G20" smd circle
			(at -16.299942 -31.949898 180)
			(size 0.450088 0.450088)
			(layers "F.Cu" "F.Mask" "F.Paste")
			(net "GND")
		)
		(pad "G21" smd circle
			(at -15.359888 -31.949898 180)
			(size 0.450088 0.450088)
			(layers "F.Cu" "F.Mask" "F.Paste")
			(net "M_I_CPU1_SA_DQ<3>")
		)
		(pad "G22" smd circle
			(at -14.420088 -31.949898 180)
			(size 0.450088 0.450088)
			(layers "F.Cu" "F.Mask" "F.Paste")
			(net "GND")
		)
		(pad "G23" smd circle
			(at -13.480034 -31.949898 180)
			(size 0.450088 0.450088)
			(layers "F.Cu" "F.Mask" "F.Paste")
			(net "GMI_CPU1_G2_CPU0_G0_TX_DP<13>")
		)
		(pad "G24" smd circle
			(at -12.53998 -31.949898 180)
			(size 0.450088 0.450088)
			(layers "F.Cu" "F.Mask" "F.Paste")
			(net "GMI_CPU1_G2_CPU0_G0_TX_DN<13>")
		)
		(pad "G25" smd circle
			(at -11.599926 -31.949898 180)
			(size 0.450088 0.450088)
			(layers "F.Cu" "F.Mask" "F.Paste")
			(net "GND")
		)
		(pad "G26" smd circle
			(at -10.659872 -31.949898 180)
			(size 0.450088 0.450088)
			(layers "F.Cu" "F.Mask" "F.Paste")
			(net "GMI_CPU1_G2_CPU0_G0_TX_DP<10>")
		)
		(pad "G27" smd circle
			(at -9.720072 -31.949898 180)
			(size 0.450088 0.450088)
			(layers "F.Cu" "F.Mask" "F.Paste")
			(net "GMI_CPU1_G2_CPU0_G0_TX_DN<10>")
		)
		(pad "G28" smd circle
			(at -8.780018 -31.949898 180)
			(size 0.450088 0.450088)
			(layers "F.Cu" "F.Mask" "F.Paste")
			(net "GND")
		)
		(pad "G29" smd circle
			(at -7.839964 -31.949898 180)
			(size 0.450088 0.450088)
			(layers "F.Cu" "F.Mask" "F.Paste")
			(net "GMI_CPU1_G2_CPU0_G0_TX_DP<7>")
		)
	)
)
